FILE_TYPE = MACRO_DRAWING;
SET COLOR_WIRE YELLOW;
SET COLOR_PROP ORANGE;
SET COLOR_DOT WHITE;
SET COLOR_ARC YELLOW;
SET COLOR_BODY GREEN;
SET COLOR_NOTE PURPLE;
SET PROP_DISPLAY VALUE;
SET PAGE_NUMBER P189;
FORCEADD Q_RES..2
(3575 3950);
FORCEPROP 1 LAST PART_NUMBER CS31002FB08
J 0
(3615 3775);
DISPLAY 0.510638 (3615 3775);
DISPLAY INVISIBLE (3615 3775);
FORCEPROP 1 LAST PACK_TYPE 0402LF
J 0
(3615 3825);
DISPLAY 0.510638 (3615 3825);
FORCEPROP 1 LAST TOLERANCE 1%
J 0
(3620 3975);
DISPLAY 0.510638 (3620 3975);
FORCEPROP 1 LAST VALUE 10K
J 0
(3620 4025);
DISPLAY 0.510638 (3620 4025);
FORCEPROP 1 LAST MATERIAL CHIP
J 0
(3615 3875);
DISPLAY 0.510638 (3615 3875);
FORCEPROP 1 LAST WATTAGE 1/16W
J 0
(3615 3925);
DISPLAY 0.510638 (3615 3925);
FORCEPROP 1 LAST $LOCATION R1339
J 0
(3620 4075);
DISPLAY 0.787234 (3620 4075);
FORCEPROP 1 LASTPIN (3575 4050) $PN 1
J 0
(3580 4012);
DISPLAY 0.787234 (3580 4012);
FORCEPROP 1 LASTPIN (3575 3850) $PN 2
J 0
(3580 3860);
DISPLAY 0.787234 (3580 3860);
FORCEPROP 2 LAST CDS_LIB pure_quanta
J 0
(3575 3950);
PAINT MONO (3575 3950);
DISPLAY INVISIBLE (3575 3950);
FORCEPROP 1 LAST PATH I100
J 0
(3625 4125);
DISPLAY 0.978723 (3625 4125);
PAINT WHITE (3625 4125);
DISPLAY INVISIBLE (3625 4125);
FORCEPROP 2 LAST CDS_LOCATION R1339
J 0
(3625 4175);
DISPLAY 1.021277 (3625 4175);
DISPLAY INVISIBLE (3625 4175);
FORCEPROP 2 LAST $SEC 1
J 0
(3625 4175);
DISPLAY 0.680851 (3625 4175);
PAINT MONO (3625 4175);
DISPLAY INVISIBLE (3625 4175);
FORCEPROP 2 LAST CDS_SEC 1
J 0
(3625 4175);
DISPLAY 1.021277 (3625 4175);
DISPLAY INVISIBLE (3625 4175);
FORCEADD OFFPAGE..2
(4500 3700);
FORCEPROP 2 LAST $XR2 202 
J 0
(4929 3700);
DISPLAY 0.638298 (4929 3700);
PAINT MONO (4929 3700);
FORCEPROP 2 LAST $XR1 131 
J 0
(4809 3700);
DISPLAY 0.638298 (4809 3700);
PAINT MONO (4809 3700);
FORCEPROP 2 LAST $XR0 183 
J 0
(4689 3700);
DISPLAY 0.638298 (4689 3700);
PAINT MONO (4689 3700);
FORCEPROP 2 LAST CDS_LIB standard
J 0
(4500 3700);
DISPLAY INVISIBLE (4500 3700);
FORCEPROP 1 LAST OFFPAGE TRUE
J 0
(4825 3575);
DISPLAY 0.872340 (4825 3575);
PAINT GREEN (4825 3575);
DISPLAY INVISIBLE (4825 3575);
FORCEPROP 1 LAST COMMENT_BODY TRUE
J 0
(4455 3605);
DISPLAY 0.872340 (4455 3605);
PAINT GREEN (4455 3605);
DISPLAY INVISIBLE (4455 3605);
FORCEPROP 2 LAST PATH I101
J 0
(4950 3750);
DISPLAY 1.021277 (4950 3750);
DISPLAY INVISIBLE (4950 3750);
FORCEADD OFFPAGE..2
(4500 3600);
FORCEPROP 2 LAST $XR1 215 
J 0
(4809 3600);
DISPLAY 0.638298 (4809 3600);
PAINT MONO (4809 3600);
FORCEPROP 2 LAST $XR0 183 
J 0
(4689 3600);
DISPLAY 0.638298 (4689 3600);
PAINT MONO (4689 3600);
FORCEPROP 2 LAST CDS_LIB standard
J 0
(4500 3600);
PAINT MONO (4500 3600);
DISPLAY INVISIBLE (4500 3600);
FORCEPROP 1 LAST OFFPAGE TRUE
J 0
(4825 3475);
DISPLAY 0.872340 (4825 3475);
PAINT GREEN (4825 3475);
DISPLAY INVISIBLE (4825 3475);
FORCEPROP 1 LAST COMMENT_BODY TRUE
J 0
(4455 3505);
DISPLAY 0.872340 (4455 3505);
PAINT GREEN (4455 3505);
DISPLAY INVISIBLE (4455 3505);
FORCEPROP 2 LAST PATH I102
J 0
(4825 3650);
DISPLAY 1.021277 (4825 3650);
DISPLAY INVISIBLE (4825 3650);
FORCEADD OFFPAGE..2
(4500 3650);
FORCEPROP 2 LAST $XR0 184 
J 0
(4689 3650);
DISPLAY 0.638298 (4689 3650);
PAINT MONO (4689 3650);
FORCEPROP 2 LAST CDS_LIB standard
J 0
(4500 3650);
PAINT MONO (4500 3650);
DISPLAY INVISIBLE (4500 3650);
FORCEPROP 1 LAST OFFPAGE TRUE
J 0
(4825 3525);
DISPLAY 0.872340 (4825 3525);
PAINT GREEN (4825 3525);
DISPLAY INVISIBLE (4825 3525);
FORCEPROP 1 LAST COMMENT_BODY TRUE
J 0
(4455 3555);
DISPLAY 0.872340 (4455 3555);
PAINT GREEN (4455 3555);
DISPLAY INVISIBLE (4455 3555);
FORCEPROP 2 LAST PATH I103
J 0
(4700 3700);
DISPLAY 1.021277 (4700 3700);
DISPLAY INVISIBLE (4700 3700);
FORCEADD OFFPAGE..2
(4500 3550);
FORCEPROP 2 LAST $XR0 183 
J 0
(4689 3550);
DISPLAY 0.638298 (4689 3550);
PAINT MONO (4689 3550);
FORCEPROP 2 LAST CDS_LIB standard
J 0
(4500 3550);
PAINT MONO (4500 3550);
DISPLAY INVISIBLE (4500 3550);
FORCEPROP 1 LAST OFFPAGE TRUE
J 0
(4825 3425);
DISPLAY 0.872340 (4825 3425);
PAINT GREEN (4825 3425);
DISPLAY INVISIBLE (4825 3425);
FORCEPROP 1 LAST COMMENT_BODY TRUE
J 0
(4455 3455);
DISPLAY 0.872340 (4455 3455);
PAINT GREEN (4455 3455);
DISPLAY INVISIBLE (4455 3455);
FORCEPROP 2 LAST PATH I104
J 0
(4700 3600);
DISPLAY 1.021277 (4700 3600);
DISPLAY INVISIBLE (4700 3600);
FORCEADD UNIVERSAL_GND..1
(3025 2800);
FORCEPROP 3 LASTPIN (3025 2850) SIG_NAME GND\g
J 0
(3035 2860);
DISPLAY 0.659574 (3035 2860);
PAINT MONO (3035 2860);
DISPLAY INVISIBLE (3035 2860);
FORCEPROP 2 LAST CDS_LIB logical_power
J 0
(3025 2800);
PAINT MONO (3025 2800);
DISPLAY INVISIBLE (3025 2800);
FORCEPROP 1 LAST HDL_POWER GND
J 1
(3050 2725);
DISPLAY 0.872340 (3050 2725);
PAINT GREEN (3050 2725);
DISPLAY INVISIBLE (3050 2725);
FORCEPROP 1 LAST PATH I105
J 0
(3100 2800);
DISPLAY 0.872340 (3100 2800);
PAINT AQUA (3100 2800);
DISPLAY INVISIBLE (3100 2800);
FORCEPROP 2 LAST ROOM IO_SLOT
J 1
(2800 2875);
DISPLAY 0.744681 (2800 2875);
DISPLAY INVISIBLE (2800 2875);
FORCEADD Q_RES..2
(3025 3025);
FORCEPROP 1 LAST PART_NUMBER CS31002FB08
J 0
(3065 2850);
DISPLAY 0.510638 (3065 2850);
DISPLAY INVISIBLE (3065 2850);
FORCEPROP 1 LAST PACK_TYPE 0402LF
J 0
(3065 2900);
DISPLAY 0.510638 (3065 2900);
FORCEPROP 1 LAST VALUE 10K
J 0
(3070 3100);
DISPLAY 0.510638 (3070 3100);
FORCEPROP 1 LAST TOLERANCE 1%
J 0
(3070 3050);
DISPLAY 0.510638 (3070 3050);
FORCEPROP 1 LAST WATTAGE 1/16W
J 0
(3065 3000);
DISPLAY 0.510638 (3065 3000);
FORCEPROP 1 LAST MATERIAL CHIP
J 0
(3065 2950);
DISPLAY 0.510638 (3065 2950);
FORCEPROP 1 LAST $LOCATION R1341
J 0
(3070 3150);
DISPLAY 0.787234 (3070 3150);
FORCEPROP 1 LASTPIN (3025 3125) $PN 1
J 0
(3030 3087);
DISPLAY 0.787234 (3030 3087);
FORCEPROP 1 LASTPIN (3025 2925) $PN 2
J 0
(3030 2935);
DISPLAY 0.787234 (3030 2935);
FORCEPROP 2 LAST CDS_LIB pure_quanta
J 0
(3025 3025);
PAINT MONO (3025 3025);
DISPLAY INVISIBLE (3025 3025);
FORCEPROP 1 LAST PATH I106
J 0
(3075 3200);
DISPLAY 0.978723 (3075 3200);
PAINT WHITE (3075 3200);
DISPLAY INVISIBLE (3075 3200);
FORCEPROP 2 LAST CDS_LOCATION R1341
J 0
(3075 3250);
DISPLAY 1.021277 (3075 3250);
DISPLAY INVISIBLE (3075 3250);
FORCEPROP 2 LAST $SEC 1
J 0
(3075 3250);
DISPLAY 0.680851 (3075 3250);
PAINT MONO (3075 3250);
DISPLAY INVISIBLE (3075 3250);
FORCEPROP 2 LAST CDS_SEC 1
J 0
(3075 3250);
DISPLAY 1.021277 (3075 3250);
DISPLAY INVISIBLE (3075 3250);
FORCEADD Q_RES..2
(2800 3025);
FORCEPROP 1 LAST PART_NUMBER CS31002FB08
J 0
(2840 2850);
DISPLAY 0.510638 (2840 2850);
DISPLAY INVISIBLE (2840 2850);
FORCEPROP 1 LAST TOLERANCE 1%
J 0
(2845 3050);
DISPLAY 0.510638 (2845 3050);
FORCEPROP 1 LAST WATTAGE 1/16W
J 0
(2840 3000);
DISPLAY 0.510638 (2840 3000);
FORCEPROP 1 LAST VALUE 10K
J 0
(2845 3100);
DISPLAY 0.510638 (2845 3100);
FORCEPROP 1 LAST MATERIAL CHIP
J 0
(2840 2950);
DISPLAY 0.510638 (2840 2950);
FORCEPROP 1 LAST PACK_TYPE 0402LF
J 0
(2840 2900);
DISPLAY 0.510638 (2840 2900);
FORCEPROP 1 LAST $LOCATION R1338
J 0
(2845 3150);
DISPLAY 0.787234 (2845 3150);
FORCEPROP 1 LASTPIN (2800 3125) $PN 1
J 0
(2805 3087);
DISPLAY 0.787234 (2805 3087);
FORCEPROP 1 LASTPIN (2800 2925) $PN 2
J 0
(2805 2935);
DISPLAY 0.787234 (2805 2935);
FORCEPROP 2 LAST CDS_LIB pure_quanta
J 0
(2800 3025);
PAINT MONO (2800 3025);
DISPLAY INVISIBLE (2800 3025);
FORCEPROP 1 LAST PATH I107
J 0
(2850 3200);
DISPLAY 0.978723 (2850 3200);
PAINT WHITE (2850 3200);
DISPLAY INVISIBLE (2850 3200);
FORCEPROP 2 LAST CDS_LOCATION R1338
J 0
(2850 3250);
DISPLAY 1.021277 (2850 3250);
DISPLAY INVISIBLE (2850 3250);
FORCEPROP 2 LAST $SEC 1
J 0
(2850 3250);
DISPLAY 0.680851 (2850 3250);
PAINT MONO (2850 3250);
DISPLAY INVISIBLE (2850 3250);
FORCEPROP 2 LAST CDS_SEC 1
J 0
(2850 3250);
DISPLAY 1.021277 (2850 3250);
DISPLAY INVISIBLE (2850 3250);
FORCEADD UNIVERSAL_GND..1
(2800 2800);
FORCEPROP 3 LASTPIN (2800 2850) SIG_NAME GND\g
J 0
(2810 2860);
DISPLAY 0.659574 (2810 2860);
PAINT MONO (2810 2860);
DISPLAY INVISIBLE (2810 2860);
FORCEPROP 2 LAST CDS_LIB logical_power
J 0
(2800 2800);
PAINT MONO (2800 2800);
DISPLAY INVISIBLE (2800 2800);
FORCEPROP 1 LAST HDL_POWER GND
J 1
(2825 2725);
DISPLAY 0.872340 (2825 2725);
PAINT GREEN (2825 2725);
DISPLAY INVISIBLE (2825 2725);
FORCEPROP 1 LAST PATH I108
J 0
(2875 2800);
DISPLAY 0.872340 (2875 2800);
PAINT AQUA (2875 2800);
DISPLAY INVISIBLE (2875 2800);
FORCEPROP 2 LAST ROOM IO_SLOT
J 1
(2575 2875);
DISPLAY 0.744681 (2575 2875);
DISPLAY INVISIBLE (2575 2875);
FORCEADD Q_RES..2
(2575 3025);
FORCEPROP 1 LAST PART_NUMBER CS31002FB08
J 0
(2615 2850);
DISPLAY 0.510638 (2615 2850);
DISPLAY INVISIBLE (2615 2850);
FORCEPROP 1 LAST WATTAGE 1/16W
J 0
(2615 3000);
DISPLAY 0.510638 (2615 3000);
FORCEPROP 1 LAST VALUE 10K
J 0
(2620 3100);
DISPLAY 0.510638 (2620 3100);
FORCEPROP 1 LAST TOLERANCE 1%
J 0
(2620 3050);
DISPLAY 0.510638 (2620 3050);
FORCEPROP 1 LAST PACK_TYPE 0402LF
J 0
(2615 2900);
DISPLAY 0.510638 (2615 2900);
FORCEPROP 1 LAST MATERIAL CHIP
J 0
(2615 2950);
DISPLAY 0.510638 (2615 2950);
FORCEPROP 1 LAST $LOCATION R2134
J 0
(2620 3150);
DISPLAY 0.787234 (2620 3150);
FORCEPROP 1 LASTPIN (2575 3125) $PN 1
J 0
(2580 3087);
DISPLAY 0.787234 (2580 3087);
PAINT MONO (2580 3087);
FORCEPROP 1 LASTPIN (2575 2925) $PN 2
J 0
(2580 2935);
DISPLAY 0.787234 (2580 2935);
PAINT MONO (2580 2935);
FORCEPROP 2 LAST CDS_LIB pure_quanta
J 0
(2575 3025);
DISPLAY INVISIBLE (2575 3025);
FORCEPROP 1 LAST PATH I109
J 0
(2625 3200);
DISPLAY 0.978723 (2625 3200);
PAINT WHITE (2625 3200);
DISPLAY INVISIBLE (2625 3200);
FORCEPROP 0 LAST CDS_LOCATION R2134
J 0
(2625 3200);
DISPLAY 1.021277 (2625 3200);
DISPLAY INVISIBLE (2625 3200);
FORCEPROP 0 LAST $SEC 1
J 0
(2625 3200);
DISPLAY 0.680851 (2625 3200);
PAINT MONO (2625 3200);
DISPLAY INVISIBLE (2625 3200);
FORCEPROP 0 LAST CDS_SEC 1
J 0
(2625 3200);
DISPLAY 1.021277 (2625 3200);
DISPLAY INVISIBLE (2625 3200);
FORCEADD UNIVERSAL_GND..1
(2575 2800);
FORCEPROP 3 LASTPIN (2575 2850) SIG_NAME GND\g
J 0
(2585 2860);
DISPLAY 0.659574 (2585 2860);
PAINT MONO (2585 2860);
DISPLAY INVISIBLE (2585 2860);
FORCEPROP 2 LAST CDS_LIB logical_power
J 0
(2575 2800);
DISPLAY INVISIBLE (2575 2800);
FORCEPROP 1 LAST HDL_POWER GND
J 1
(2600 2725);
DISPLAY 0.872340 (2600 2725);
PAINT GREEN (2600 2725);
DISPLAY INVISIBLE (2600 2725);
FORCEPROP 1 LAST PATH I110
J 0
(2650 2800);
DISPLAY 0.872340 (2650 2800);
PAINT AQUA (2650 2800);
DISPLAY INVISIBLE (2650 2800);
FORCEPROP 2 LAST ROOM IO_SLOT
J 1
(2350 2875);
DISPLAY 0.744681 (2350 2875);
DISPLAY INVISIBLE (2350 2875);
FORCEADD OFFPAGE..2
(4500 3500);
FORCEPROP 2 LAST $XR1 183 
J 0
(4809 3500);
DISPLAY 0.638298 (4809 3500);
PAINT MONO (4809 3500);
FORCEPROP 2 LAST $XR0 198 
J 0
(4689 3500);
DISPLAY 0.638298 (4689 3500);
PAINT MONO (4689 3500);
FORCEPROP 2 LAST CDS_LIB standard
J 0
(4500 3500);
PAINT MONO (4500 3500);
DISPLAY INVISIBLE (4500 3500);
FORCEPROP 1 LAST OFFPAGE TRUE
J 0
(4825 3375);
DISPLAY 0.872340 (4825 3375);
PAINT GREEN (4825 3375);
DISPLAY INVISIBLE (4825 3375);
FORCEPROP 1 LAST COMMENT_BODY TRUE
J 0
(4455 3405);
DISPLAY 0.872340 (4455 3405);
PAINT GREEN (4455 3405);
DISPLAY INVISIBLE (4455 3405);
FORCEPROP 2 LAST PATH I111
J 0
(4825 3550);
DISPLAY 1.021277 (4825 3550);
DISPLAY INVISIBLE (4825 3550);
FORCEADD UNIVERSAL_POWER..1
(4000 4275);
FORCEPROP 3 LASTPIN (4000 4225) SIG_NAME P1V05_PCH_AUX\g
J 0
(4010 4235);
DISPLAY 0.659574 (4010 4235);
PAINT MONO (4010 4235);
DISPLAY INVISIBLE (4010 4235);
FORCEPROP 1 LAST HDL_POWER P1V05_PCH_AUX
J 1
(4000 4325);
DISPLAY 0.702128 (4000 4325);
PAINT GREEN (4000 4325);
FORCEPROP 2 LAST CDS_LIB logical_power
J 0
(4000 4275);
PAINT MONO (4000 4275);
DISPLAY INVISIBLE (4000 4275);
FORCEPROP 1 LAST PATH I112
J 0
(4050 4300);
DISPLAY 0.872340 (4050 4300);
PAINT AQUA (4050 4300);
DISPLAY INVISIBLE (4050 4300);
FORCEADD Q_RES..2
(4000 3950);
FORCEPROP 1 LAST PART_NUMBER CS31002FB08
J 0
(4040 3775);
DISPLAY 0.404255 (4040 3775);
DISPLAY INVISIBLE (4040 3775);
FORCEPROP 1 LAST TOLERANCE 1%
J 0
(4045 3975);
DISPLAY 0.510638 (4045 3975);
FORCEPROP 1 LAST VALUE 10K
J 0
(4045 4025);
DISPLAY 0.510638 (4045 4025);
FORCEPROP 1 LAST WATTAGE 1/16W
J 0
(4040 3925);
DISPLAY 0.510638 (4040 3925);
FORCEPROP 1 LAST MATERIAL CHIP
J 0
(4040 3875);
DISPLAY 0.510638 (4040 3875);
FORCEPROP 1 LAST PACK_TYPE 0402LF
J 0
(4040 3825);
DISPLAY 0.510638 (4040 3825);
FORCEPROP 1 LAST $LOCATION R1343
J 0
(4045 4075);
DISPLAY 0.787234 (4045 4075);
FORCEPROP 1 LASTPIN (4000 4050) $PN 1
J 0
(4005 4012);
DISPLAY 0.787234 (4005 4012);
FORCEPROP 1 LASTPIN (4000 3850) $PN 2
J 0
(4005 3860);
DISPLAY 0.787234 (4005 3860);
FORCEPROP 2 LAST CDS_LIB pure_quanta
J 0
(4000 3950);
PAINT MONO (4000 3950);
DISPLAY INVISIBLE (4000 3950);
FORCEPROP 1 LAST PATH I113
J 0
(4050 4125);
DISPLAY 0.978723 (4050 4125);
PAINT WHITE (4050 4125);
DISPLAY INVISIBLE (4050 4125);
FORCEPROP 2 LAST CDS_LOCATION R1343
J 0
(4050 4175);
DISPLAY 1.021277 (4050 4175);
DISPLAY INVISIBLE (4050 4175);
FORCEPROP 2 LAST $SEC 1
J 0
(4050 4175);
DISPLAY 0.680851 (4050 4175);
PAINT MONO (4050 4175);
DISPLAY INVISIBLE (4050 4175);
FORCEPROP 2 LAST CDS_SEC 1
J 0
(4050 4175);
DISPLAY 1.021277 (4050 4175);
DISPLAY INVISIBLE (4050 4175);
FORCEADD Q_RES..2
(4250 3950);
FORCEPROP 1 LAST PART_NUMBER CS31002FB08
J 0
(4290 3775);
DISPLAY 0.510638 (4290 3775);
DISPLAY INVISIBLE (4290 3775);
FORCEPROP 1 LAST PACK_TYPE 0402LF
J 0
(4290 3825);
DISPLAY 0.510638 (4290 3825);
FORCEPROP 1 LAST TOLERANCE 1%
J 0
(4295 3975);
DISPLAY 0.510638 (4295 3975);
FORCEPROP 1 LAST WATTAGE 1/16W
J 0
(4290 3925);
DISPLAY 0.510638 (4290 3925);
FORCEPROP 1 LAST VALUE 10K
J 0
(4295 4025);
DISPLAY 0.510638 (4295 4025);
FORCEPROP 1 LAST MATERIAL CHIP
J 0
(4290 3875);
DISPLAY 0.510638 (4290 3875);
FORCEPROP 1 LAST $LOCATION R1342
J 0
(4295 4075);
DISPLAY 0.787234 (4295 4075);
FORCEPROP 1 LASTPIN (4250 4050) $PN 1
J 0
(4255 4012);
DISPLAY 0.787234 (4255 4012);
FORCEPROP 1 LASTPIN (4250 3850) $PN 2
J 0
(4255 3860);
DISPLAY 0.787234 (4255 3860);
FORCEPROP 2 LAST CDS_LIB pure_quanta
J 0
(4250 3950);
PAINT MONO (4250 3950);
DISPLAY INVISIBLE (4250 3950);
FORCEPROP 1 LAST PATH I114
J 0
(4300 4125);
DISPLAY 0.978723 (4300 4125);
PAINT WHITE (4300 4125);
DISPLAY INVISIBLE (4300 4125);
FORCEPROP 2 LAST CDS_LOCATION R1342
J 0
(4300 4175);
DISPLAY 1.021277 (4300 4175);
DISPLAY INVISIBLE (4300 4175);
FORCEPROP 2 LAST $SEC 1
J 0
(4300 4175);
DISPLAY 0.680851 (4300 4175);
PAINT MONO (4300 4175);
DISPLAY INVISIBLE (4300 4175);
FORCEPROP 2 LAST CDS_SEC 1
J 0
(4300 4175);
DISPLAY 1.021277 (4300 4175);
DISPLAY INVISIBLE (4300 4175);
FORCEADD SW_PUSHBUTTON4P_24..1
(1150 1550);
FORCEPROP 1 LAST PART_NUMBER DHP00061N15
J 0
(1076 1710);
DISPLAY 0.723404 (1076 1710);
PAINT GREEN (1076 1710);
DISPLAY INVISIBLE (1076 1710);
FORCEPROP 2 LAST VALUE SW4S_DTSM-61N-S-Q-T/R
J 0
(1075 1800);
DISPLAY 1.021277 (1075 1800);
FORCEPROP 1 LAST MATERIAL MECH
J 0
(1076 1660);
DISPLAY 0.723404 (1076 1660);
PAINT GREEN (1076 1660);
FORCEPROP 2 LAST PART_TYPE SMLF
J 0
(1075 1850);
DISPLAY 1.021277 (1075 1850);
FORCEPROP 1 LAST $LOCATION SW5
J 0
(1076 1755);
DISPLAY 0.723404 (1076 1755);
PAINT GREEN (1076 1755);
FORCEPROP 0 LASTPIN (925 1500) $PN 1
J 2
(915 1510);
DISPLAY 0.680851 (915 1510);
PAINT MONO (915 1510);
FORCEPROP 0 LASTPIN (925 1550) $PN 2
J 2
(915 1560);
DISPLAY 0.680851 (915 1560);
PAINT MONO (915 1560);
FORCEPROP 0 LASTPIN (1375 1500) $PN 3
J 0
(1385 1510);
DISPLAY 0.680851 (1385 1510);
PAINT MONO (1385 1510);
FORCEPROP 0 LASTPIN (1375 1550) $PN 4
J 0
(1385 1560);
DISPLAY 0.680851 (1385 1560);
PAINT MONO (1385 1560);
FORCEPROP 1 LAST NEEDS_NO_SIZE TRUE
J 0
(1225 1450);
DISPLAY 0.468085 (1225 1450);
PAINT GREEN (1225 1450);
DISPLAY INVISIBLE (1225 1450);
FORCEPROP 2 LAST CDS_LIB pure_quanta
J 0
(1150 1550);
DISPLAY INVISIBLE (1150 1550);
FORCEPROP 1 LAST CDS_LMAN_SYM_OUTLINE -75,100,75,-100
J 0
(1150 1550);
DISPLAY 0.468085 (1150 1550);
PAINT GREEN (1150 1550);
DISPLAY INVISIBLE (1150 1550);
FORCEPROP 1 LAST PATH I122
J 0
(1150 1550);
DISPLAY 0.723404 (1150 1550);
PAINT GREEN (1150 1550);
DISPLAY INVISIBLE (1150 1550);
FORCEPROP 0 LAST CDS_LOCATION SW5
J 0
(1075 1900);
DISPLAY 1.021277 (1075 1900);
DISPLAY INVISIBLE (1075 1900);
FORCEPROP 0 LAST $SEC 1
J 0
(1075 1900);
DISPLAY 0.680851 (1075 1900);
PAINT MONO (1075 1900);
DISPLAY INVISIBLE (1075 1900);
FORCEPROP 0 LAST CDS_SEC 1
J 0
(1075 1900);
DISPLAY 1.021277 (1075 1900);
DISPLAY INVISIBLE (1075 1900);
FORCEADD Q_RES..1
(-550 1550);
FORCEPROP 1 LAST PART_NUMBER CS21002FB06
J 0
(-700 1475);
DISPLAY 0.638298 (-700 1475);
DISPLAY INVISIBLE (-700 1475);
FORCEPROP 1 LAST MATERIAL CHIP
J 0
(-150 1550);
DISPLAY 0.638298 (-150 1550);
FORCEPROP 1 LAST TOLERANCE 1%
J 0
(-250 1550);
DISPLAY 0.638298 (-250 1550);
FORCEPROP 1 LAST VALUE 1K
J 2
(-300 1550);
DISPLAY 0.638298 (-300 1550);
FORCEPROP 1 LAST $LOCATION R1333
J 0
(-850 1550);
DISPLAY 0.638298 (-850 1550);
FORCEPROP 1 LASTPIN (-650 1550) $PN 1
J 0
(-638 1562);
DISPLAY 0.787234 (-638 1562);
FORCEPROP 1 LASTPIN (-450 1550) $PN 2
J 0
(-488 1562);
DISPLAY 0.787234 (-488 1562);
FORCEPROP 2 LAST CDS_LIB pure_quanta
J 0
(-550 1550);
PAINT MONO (-550 1550);
DISPLAY INVISIBLE (-550 1550);
FORCEPROP 1 LAST PACK_TYPE 0402LF
J 0
(-700 1425);
DISPLAY 0.638298 (-700 1425);
DISPLAY INVISIBLE (-700 1425);
FORCEPROP 1 LAST WATTAGE 1/16W
J 2
(-325 1425);
DISPLAY 0.638298 (-325 1425);
DISPLAY INVISIBLE (-325 1425);
FORCEPROP 1 LAST PATH I123
J 0
(-600 1700);
DISPLAY 0.978723 (-600 1700);
PAINT WHITE (-600 1700);
DISPLAY INVISIBLE (-600 1700);
FORCEPROP 2 LAST CDS_LOCATION R1333
J 0
(-600 1750);
DISPLAY 1.021277 (-600 1750);
DISPLAY INVISIBLE (-600 1750);
FORCEPROP 2 LAST $SEC 1
J 0
(-600 1750);
DISPLAY 0.680851 (-600 1750);
PAINT MONO (-600 1750);
DISPLAY INVISIBLE (-600 1750);
FORCEPROP 2 LAST CDS_SEC 1
J 0
(-600 1750);
DISPLAY 1.021277 (-600 1750);
DISPLAY INVISIBLE (-600 1750);
FORCEADD UNIVERSAL_GND..1
(-975 1450);
FORCEPROP 3 LASTPIN (-975 1500) SIG_NAME GND\g
J 0
(-965 1510);
DISPLAY 0.659574 (-965 1510);
PAINT MONO (-965 1510);
DISPLAY INVISIBLE (-965 1510);
FORCEPROP 2 LAST CDS_LIB logical_power
J 0
(-975 1450);
DISPLAY INVISIBLE (-975 1450);
FORCEPROP 1 LAST HDL_POWER GND
J 1
(-950 1375);
DISPLAY 0.872340 (-950 1375);
PAINT GREEN (-950 1375);
DISPLAY INVISIBLE (-950 1375);
FORCEPROP 1 LAST PATH I124
J 0
(-900 1450);
DISPLAY 0.872340 (-900 1450);
PAINT AQUA (-900 1450);
DISPLAY INVISIBLE (-900 1450);
FORCEPROP 2 LAST ROOM IO_SLOT
J 1
(-1200 1525);
DISPLAY 0.744681 (-1200 1525);
DISPLAY INVISIBLE (-1200 1525);
FORCEADD OFFPAGE..2
(4250 1550);
FORCEPROP 2 LAST $XR0 185 
J 0
(4439 1550);
DISPLAY 0.638298 (4439 1550);
PAINT MONO (4439 1550);
FORCEPROP 2 LAST CDS_LIB standard
J 0
(4250 1550);
PAINT MONO (4250 1550);
DISPLAY INVISIBLE (4250 1550);
FORCEPROP 1 LAST OFFPAGE TRUE
J 0
(4575 1425);
DISPLAY 0.872340 (4575 1425);
PAINT GREEN (4575 1425);
DISPLAY INVISIBLE (4575 1425);
FORCEPROP 1 LAST COMMENT_BODY TRUE
J 0
(4205 1455);
DISPLAY 0.872340 (4205 1455);
PAINT GREEN (4205 1455);
DISPLAY INVISIBLE (4205 1455);
FORCEPROP 2 LAST PATH I125
J 0
(4450 1600);
DISPLAY 1.021277 (4450 1600);
DISPLAY INVISIBLE (4450 1600);
FORCEADD UNIVERSAL_POWER..1
(2900 2375);
FORCEPROP 3 LASTPIN (2900 2325) SIG_NAME P3V3_RTC_AUX\g
J 0
(2910 2335);
DISPLAY 0.659574 (2910 2335);
PAINT MONO (2910 2335);
DISPLAY INVISIBLE (2910 2335);
FORCEPROP 1 LAST HDL_POWER P3V3_RTC_AUX
J 1
(2900 2425);
DISPLAY 0.702128 (2900 2425);
PAINT GREEN (2900 2425);
FORCEPROP 2 LAST CDS_LIB logical_power
J 0
(2900 2375);
PAINT MONO (2900 2375);
DISPLAY INVISIBLE (2900 2375);
FORCEPROP 1 LAST PATH I126
J 0
(2950 2400);
DISPLAY 0.872340 (2950 2400);
PAINT AQUA (2950 2400);
DISPLAY INVISIBLE (2950 2400);
FORCEADD Q_RES..2
(2900 2050);
FORCEPROP 1 LAST PART_NUMBER CS32002FB06
J 0
(2940 1875);
DISPLAY 0.404255 (2940 1875);
DISPLAY INVISIBLE (2940 1875);
FORCEPROP 1 LAST PACK_TYPE 0402LF
J 0
(2940 1925);
DISPLAY 0.510638 (2940 1925);
FORCEPROP 1 LAST WATTAGE 1/16W
J 0
(2940 2025);
DISPLAY 0.510638 (2940 2025);
FORCEPROP 1 LAST TOLERANCE 1%
J 0
(2945 2075);
DISPLAY 0.510638 (2945 2075);
FORCEPROP 1 LAST VALUE 20K
J 0
(2945 2125);
DISPLAY 0.510638 (2945 2125);
FORCEPROP 1 LAST MATERIAL CHIP
J 0
(2940 1975);
DISPLAY 0.510638 (2940 1975);
FORCEPROP 1 LAST $LOCATION R1340
J 0
(2945 2175);
DISPLAY 0.787234 (2945 2175);
FORCEPROP 1 LASTPIN (2900 2150) $PN 1
J 0
(2905 2112);
DISPLAY 0.787234 (2905 2112);
FORCEPROP 1 LASTPIN (2900 1950) $PN 2
J 0
(2905 1960);
DISPLAY 0.787234 (2905 1960);
FORCEPROP 2 LAST CDS_LIB pure_quanta
J 0
(2900 2050);
PAINT MONO (2900 2050);
DISPLAY INVISIBLE (2900 2050);
FORCEPROP 1 LAST PATH I127
J 0
(2950 2225);
DISPLAY 0.978723 (2950 2225);
PAINT WHITE (2950 2225);
DISPLAY INVISIBLE (2950 2225);
FORCEPROP 2 LAST CDS_LOCATION R1340
J 0
(2950 2275);
DISPLAY 1.021277 (2950 2275);
DISPLAY INVISIBLE (2950 2275);
FORCEPROP 2 LAST $SEC 1
J 0
(2950 2275);
DISPLAY 0.680851 (2950 2275);
PAINT MONO (2950 2275);
DISPLAY INVISIBLE (2950 2275);
FORCEPROP 2 LAST CDS_SEC 1
J 0
(2950 2275);
DISPLAY 1.021277 (2950 2275);
DISPLAY INVISIBLE (2950 2275);
FORCEADD Q_CAP..1
(3000 1125);
FORCEPROP 1 LAST PART_NUMBER CH5104KEB02
J 0
(3050 975);
DISPLAY 0.510638 (3050 975);
DISPLAY INVISIBLE (3050 975);
FORCEPROP 1 LAST MATERIAL X6S
J 0
(3050 1025);
DISPLAY 0.510638 (3050 1025);
FORCEPROP 1 LAST PACK_TYPE C0402
J 0
(3050 925);
DISPLAY 0.510638 (3050 925);
FORCEPROP 1 LAST VALUE 1UF
J 0
(3050 1175);
DISPLAY 0.510638 (3050 1175);
FORCEPROP 1 LAST VOLTAGE 25V
J 0
(3050 1125);
DISPLAY 0.510638 (3050 1125);
FORCEPROP 1 LAST TOLERANCE 10%
J 0
(3050 1075);
DISPLAY 0.510638 (3050 1075);
FORCEPROP 1 LAST $LOCATION C1177
J 0
(3050 1225);
DISPLAY 0.978723 (3050 1225);
FORCEPROP 1 LASTPIN (3000 1225) $PN 1
J 0
(3010 1205);
DISPLAY 0.787234 (3010 1205);
FORCEPROP 1 LASTPIN (3000 1025) $PN 2
J 0
(3010 1005);
DISPLAY 0.787234 (3010 1005);
FORCEPROP 2 LAST CDS_LIB pure_quanta
J 0
(3000 1125);
PAINT MONO (3000 1125);
DISPLAY INVISIBLE (3000 1125);
FORCEPROP 1 LAST PATH I128
J 0
(3050 1275);
DISPLAY 0.978723 (3050 1275);
PAINT WHITE (3050 1275);
DISPLAY INVISIBLE (3050 1275);
FORCEPROP 2 LAST CDS_LOCATION C1177
J 0
(3050 1325);
DISPLAY 1.021277 (3050 1325);
DISPLAY INVISIBLE (3050 1325);
FORCEPROP 2 LAST $SEC 1
J 0
(3050 1325);
DISPLAY 0.680851 (3050 1325);
PAINT MONO (3050 1325);
DISPLAY INVISIBLE (3050 1325);
FORCEPROP 2 LAST CDS_SEC 1
J 0
(3050 1325);
DISPLAY 1.021277 (3050 1325);
DISPLAY INVISIBLE (3050 1325);
FORCEADD UNIVERSAL_GND..1
(3000 900);
FORCEPROP 3 LASTPIN (3000 950) SIG_NAME GND\g
J 0
(3010 960);
DISPLAY 0.659574 (3010 960);
PAINT MONO (3010 960);
DISPLAY INVISIBLE (3010 960);
FORCEPROP 2 LAST CDS_LIB logical_power
J 0
(3000 900);
PAINT MONO (3000 900);
DISPLAY INVISIBLE (3000 900);
FORCEPROP 1 LAST HDL_POWER GND
J 1
(3025 825);
DISPLAY 0.872340 (3025 825);
PAINT GREEN (3025 825);
DISPLAY INVISIBLE (3025 825);
FORCEPROP 1 LAST PATH I129
J 0
(3075 900);
DISPLAY 0.872340 (3075 900);
PAINT AQUA (3075 900);
DISPLAY INVISIBLE (3075 900);
FORCEADD OFFPAGE..2
(4500 3450);
FORCEPROP 2 LAST $XR0 184 
J 0
(4689 3450);
DISPLAY 0.638298 (4689 3450);
PAINT MONO (4689 3450);
FORCEPROP 2 LAST CDS_LIB standard
J 0
(4500 3450);
PAINT MONO (4500 3450);
DISPLAY INVISIBLE (4500 3450);
FORCEPROP 1 LAST OFFPAGE TRUE
J 0
(4825 3325);
DISPLAY 0.872340 (4825 3325);
PAINT GREEN (4825 3325);
DISPLAY INVISIBLE (4825 3325);
FORCEPROP 1 LAST COMMENT_BODY TRUE
J 0
(4455 3355);
DISPLAY 0.872340 (4455 3355);
PAINT GREEN (4455 3355);
DISPLAY INVISIBLE (4455 3355);
FORCEPROP 2 LAST PATH I130
J 0
(4700 3500);
DISPLAY 1.021277 (4700 3500);
DISPLAY INVISIBLE (4700 3500);
FORCEADD OFFPAGE..2
(4500 3400);
FORCEPROP 2 LAST $XR0 184 
J 0
(4689 3400);
DISPLAY 0.638298 (4689 3400);
PAINT MONO (4689 3400);
FORCEPROP 2 LAST CDS_LIB standard
J 0
(4500 3400);
PAINT MONO (4500 3400);
DISPLAY INVISIBLE (4500 3400);
FORCEPROP 1 LAST OFFPAGE TRUE
J 0
(4825 3275);
DISPLAY 0.872340 (4825 3275);
PAINT GREEN (4825 3275);
DISPLAY INVISIBLE (4825 3275);
FORCEPROP 1 LAST COMMENT_BODY TRUE
J 0
(4455 3305);
DISPLAY 0.872340 (4455 3305);
PAINT GREEN (4455 3305);
DISPLAY INVISIBLE (4455 3305);
FORCEPROP 2 LAST PATH I131
J 0
(4700 3450);
DISPLAY 1.021277 (4700 3450);
DISPLAY INVISIBLE (4700 3450);
FORCEADD Q_RES..1
(-350 3450);
FORCEPROP 1 LAST PART_NUMBER CS21002FB06
J 0
(-500 3375);
DISPLAY 0.638298 (-500 3375);
DISPLAY INVISIBLE (-500 3375);
FORCEPROP 1 LAST TOLERANCE 1%
J 0
(-50 3450);
DISPLAY 0.638298 (-50 3450);
FORCEPROP 1 LAST VALUE 1K
J 2
(-100 3450);
DISPLAY 0.638298 (-100 3450);
FORCEPROP 1 LAST MATERIAL CHIP
J 0
(50 3450);
DISPLAY 0.638298 (50 3450);
FORCEPROP 1 LAST $LOCATION R3039
J 0
(-650 3450);
DISPLAY 0.638298 (-650 3450);
FORCEPROP 1 LASTPIN (-450 3450) $PN 1
J 0
(-438 3462);
DISPLAY 0.787234 (-438 3462);
FORCEPROP 1 LASTPIN (-250 3450) $PN 2
J 0
(-288 3462);
DISPLAY 0.787234 (-288 3462);
FORCEPROP 1 LAST WATTAGE 1/16W
J 2
(-125 3325);
DISPLAY 0.638298 (-125 3325);
DISPLAY INVISIBLE (-125 3325);
FORCEPROP 1 LAST PACK_TYPE 0402LF
J 0
(-500 3325);
DISPLAY 0.638298 (-500 3325);
DISPLAY INVISIBLE (-500 3325);
FORCEPROP 2 LAST CDS_LIB pure_quanta
J 0
(-350 3450);
PAINT MONO (-350 3450);
DISPLAY INVISIBLE (-350 3450);
FORCEPROP 1 LAST PATH I132
J 0
(-400 3600);
DISPLAY 0.978723 (-400 3600);
PAINT WHITE (-400 3600);
DISPLAY INVISIBLE (-400 3600);
FORCEPROP 2 LAST CDS_LOCATION R3039
J 0
(-400 3650);
DISPLAY 1.021277 (-400 3650);
DISPLAY INVISIBLE (-400 3650);
FORCEPROP 2 LAST $SEC 1
J 0
(-400 3650);
DISPLAY 0.680851 (-400 3650);
PAINT MONO (-400 3650);
DISPLAY INVISIBLE (-400 3650);
FORCEPROP 2 LAST CDS_SEC 1
J 0
(-400 3650);
DISPLAY 1.021277 (-400 3650);
DISPLAY INVISIBLE (-400 3650);
FORCEADD Q_RES..1
(-350 3400);
FORCEPROP 1 LAST PART_NUMBER CS21002FB06
J 0
(-500 3325);
DISPLAY 0.638298 (-500 3325);
DISPLAY INVISIBLE (-500 3325);
FORCEPROP 1 LAST MATERIAL CHIP
J 0
(50 3400);
DISPLAY 0.638298 (50 3400);
FORCEPROP 1 LAST PACK_TYPE 0402LF
J 0
(-500 3275);
DISPLAY 0.638298 (-500 3275);
FORCEPROP 1 LAST WATTAGE 1/16W
J 2
(-125 3275);
DISPLAY 0.638298 (-125 3275);
FORCEPROP 1 LAST TOLERANCE 1%
J 0
(-50 3400);
DISPLAY 0.638298 (-50 3400);
FORCEPROP 1 LAST VALUE 1K
J 2
(-100 3400);
DISPLAY 0.638298 (-100 3400);
FORCEPROP 1 LAST $LOCATION R1335
J 0
(-650 3400);
DISPLAY 0.638298 (-650 3400);
FORCEPROP 1 LASTPIN (-450 3400) $PN 1
J 0
(-438 3412);
DISPLAY 0.787234 (-438 3412);
FORCEPROP 1 LASTPIN (-250 3400) $PN 2
J 0
(-288 3412);
DISPLAY 0.787234 (-288 3412);
FORCEPROP 2 LAST CDS_LIB pure_quanta
J 0
(-350 3400);
PAINT MONO (-350 3400);
DISPLAY INVISIBLE (-350 3400);
FORCEPROP 1 LAST PATH I133
J 0
(-400 3550);
DISPLAY 0.978723 (-400 3550);
PAINT WHITE (-400 3550);
DISPLAY INVISIBLE (-400 3550);
FORCEPROP 2 LAST CDS_LOCATION R1335
J 0
(-400 3600);
DISPLAY 1.021277 (-400 3600);
DISPLAY INVISIBLE (-400 3600);
FORCEPROP 2 LAST $SEC 1
J 0
(-400 3600);
DISPLAY 0.680851 (-400 3600);
PAINT MONO (-400 3600);
DISPLAY INVISIBLE (-400 3600);
FORCEPROP 2 LAST CDS_SEC 1
J 0
(-400 3600);
DISPLAY 1.021277 (-400 3600);
DISPLAY INVISIBLE (-400 3600);
FORCEADD CONN14_210HP207GBR1..1
(1375 3550);
FORCEPROP 1 LAST PART_NUMBER DFHD14MS170
J 0
(1281 3884);
DISPLAY 0.723404 (1281 3884);
PAINT GREEN (1281 3884);
DISPLAY INVISIBLE (1281 3884);
FORCEPROP 2 LAST PART_TYPE THLF
J 0
(1300 4125);
DISPLAY 1.021277 (1300 4125);
FORCEPROP 1 LAST MATERIAL IO
J 0
(1281 3757);
DISPLAY 0.723404 (1281 3757);
PAINT GREEN (1281 3757);
FORCEPROP 2 LAST VALUE CONN14_210-HP2-07GBR1
J 0
(1300 4075);
DISPLAY 1.021277 (1300 4075);
FORCEPROP 1 LAST LOCATION J104
J 0
(1281 4031);
DISPLAY 0.723404 (1281 4031);
PAINT GREEN (1281 4031);
FORCEPROP 0 LASTPIN (1125 3700) $PN 1
J 2
(1115 3710);
DISPLAY 0.680851 (1115 3710);
PAINT MONO (1115 3710);
FORCEPROP 0 LASTPIN (1625 3700) $PN 2
J 0
(1635 3710);
DISPLAY 0.680851 (1635 3710);
PAINT MONO (1635 3710);
FORCEPROP 0 LASTPIN (1125 3650) $PN 3
J 2
(1115 3660);
DISPLAY 0.680851 (1115 3660);
PAINT MONO (1115 3660);
FORCEPROP 0 LASTPIN (1625 3650) $PN 4
J 0
(1635 3660);
DISPLAY 0.680851 (1635 3660);
PAINT MONO (1635 3660);
FORCEPROP 0 LASTPIN (1125 3600) $PN 5
J 2
(1115 3610);
DISPLAY 0.680851 (1115 3610);
PAINT MONO (1115 3610);
FORCEPROP 0 LASTPIN (1625 3600) $PN 6
J 0
(1635 3610);
DISPLAY 0.680851 (1635 3610);
PAINT MONO (1635 3610);
FORCEPROP 0 LASTPIN (1125 3550) $PN 7
J 2
(1115 3560);
DISPLAY 0.680851 (1115 3560);
PAINT MONO (1115 3560);
FORCEPROP 0 LASTPIN (1625 3550) $PN 8
J 0
(1635 3560);
DISPLAY 0.680851 (1635 3560);
PAINT MONO (1635 3560);
FORCEPROP 0 LASTPIN (1125 3500) $PN 9
J 2
(1115 3510);
DISPLAY 0.680851 (1115 3510);
PAINT MONO (1115 3510);
FORCEPROP 0 LASTPIN (1625 3500) $PN 10
J 0
(1635 3510);
DISPLAY 0.680851 (1635 3510);
PAINT MONO (1635 3510);
FORCEPROP 0 LASTPIN (1125 3450) $PN 11
J 2
(1115 3460);
DISPLAY 0.680851 (1115 3460);
PAINT MONO (1115 3460);
FORCEPROP 0 LASTPIN (1625 3450) $PN 12
J 0
(1635 3460);
DISPLAY 0.680851 (1635 3460);
PAINT MONO (1635 3460);
FORCEPROP 0 LASTPIN (1125 3400) $PN 13
J 2
(1115 3410);
DISPLAY 0.680851 (1115 3410);
PAINT MONO (1115 3410);
FORCEPROP 0 LASTPIN (1625 3400) $PN 14
J 0
(1635 3410);
DISPLAY 0.680851 (1635 3410);
PAINT MONO (1635 3410);
FORCEPROP 2 LAST CDS_LIB pure_quanta
J 0
(1375 3550);
DISPLAY INVISIBLE (1375 3550);
FORCEPROP 1 LAST NEEDS_NO_SIZE TRUE
J 0
(1375 3550);
DISPLAY 0.723404 (1375 3550);
PAINT GREEN (1375 3550);
DISPLAY INVISIBLE (1375 3550);
FORCEPROP 1 LAST CDS_LMAN_SYM_OUTLINE -100,200,100,-200
J 0
(1375 3550);
DISPLAY 0.468085 (1375 3550);
PAINT GREEN (1375 3550);
DISPLAY INVISIBLE (1375 3550);
FORCEPROP 1 LAST PATH I134
J 0
(1375 3550);
DISPLAY 0.723404 (1375 3550);
PAINT GREEN (1375 3550);
DISPLAY INVISIBLE (1375 3550);
FORCEPROP 0 LAST $SEC 1
J 0
(1300 4175);
DISPLAY 0.680851 (1300 4175);
PAINT MONO (1300 4175);
DISPLAY INVISIBLE (1300 4175);
FORCEPROP 0 LAST CDS_SEC 1
J 0
(1300 4175);
DISPLAY 1.021277 (1300 4175);
DISPLAY INVISIBLE (1300 4175);
FORCEADD Q_RES..1
(-350 3700);
FORCEPROP 1 LAST PART_NUMBER CS21002FB06
J 0
(-500 3625);
DISPLAY 0.638298 (-500 3625);
DISPLAY INVISIBLE (-500 3625);
FORCEPROP 1 LAST VALUE 1K
J 2
(-175 3700);
DISPLAY 0.510638 (-175 3700);
FORCEPROP 1 LAST MATERIAL CHIP
J 0
(-75 3700);
DISPLAY 0.510638 (-75 3700);
FORCEPROP 1 LAST TOLERANCE 1%
J 0
(-150 3700);
DISPLAY 0.510638 (-150 3700);
FORCEPROP 1 LAST $LOCATION R2133
J 0
(-650 3700);
DISPLAY 0.638298 (-650 3700);
FORCEPROP 1 LASTPIN (-450 3700) $PN 1
J 0
(-438 3712);
DISPLAY 0.787234 (-438 3712);
PAINT MONO (-438 3712);
FORCEPROP 1 LASTPIN (-250 3700) $PN 2
J 0
(-288 3712);
DISPLAY 0.787234 (-288 3712);
PAINT MONO (-288 3712);
FORCEPROP 1 LAST PACK_TYPE 0402LF
J 0
(-500 3575);
DISPLAY 0.638298 (-500 3575);
DISPLAY INVISIBLE (-500 3575);
FORCEPROP 1 LAST WATTAGE 1/16W
J 2
(-125 3575);
DISPLAY 0.638298 (-125 3575);
DISPLAY INVISIBLE (-125 3575);
FORCEPROP 2 LAST CDS_LIB pure_quanta
J 0
(-350 3700);
DISPLAY INVISIBLE (-350 3700);
FORCEPROP 1 LAST PATH I86
J 0
(-400 3850);
DISPLAY 0.978723 (-400 3850);
PAINT WHITE (-400 3850);
DISPLAY INVISIBLE (-400 3850);
FORCEPROP 0 LAST CDS_LOCATION R2133
J 0
(-650 3750);
DISPLAY 1.021277 (-650 3750);
DISPLAY INVISIBLE (-650 3750);
FORCEPROP 0 LAST $SEC 1
J 0
(-650 3750);
DISPLAY 0.680851 (-650 3750);
PAINT MONO (-650 3750);
DISPLAY INVISIBLE (-650 3750);
FORCEPROP 0 LAST CDS_SEC 1
J 0
(-650 3750);
DISPLAY 1.021277 (-650 3750);
DISPLAY INVISIBLE (-650 3750);
FORCEADD Q_RES..1
(-350 3550);
FORCEPROP 1 LAST PART_NUMBER CS21002FB06
J 0
(-500 3150);
DISPLAY 0.638298 (-500 3150);
DISPLAY INVISIBLE (-500 3150);
FORCEPROP 1 LAST VALUE 1K
J 2
(-175 3550);
DISPLAY 0.510638 (-175 3550);
FORCEPROP 1 LAST MATERIAL CHIP
J 0
(-75 3550);
DISPLAY 0.510638 (-75 3550);
FORCEPROP 1 LAST $LOCATION R1324
J 0
(-650 3550);
DISPLAY 0.638298 (-650 3550);
FORCEPROP 1 LASTPIN (-450 3550) $PN 1
J 0
(-438 3562);
DISPLAY 0.787234 (-438 3562);
FORCEPROP 1 LASTPIN (-250 3550) $PN 2
J 0
(-288 3562);
DISPLAY 0.787234 (-288 3562);
FORCEPROP 1 LAST WATTAGE 1/16W
J 2
(-125 3100);
DISPLAY 0.638298 (-125 3100);
DISPLAY INVISIBLE (-125 3100);
FORCEPROP 1 LAST TOLERANCE 1%
J 0
(-150 3550);
DISPLAY 0.510638 (-150 3550);
DISPLAY INVISIBLE (-150 3550);
FORCEPROP 1 LAST PACK_TYPE 0402LF
J 0
(-500 3100);
DISPLAY 0.638298 (-500 3100);
DISPLAY INVISIBLE (-500 3100);
FORCEPROP 2 LAST CDS_LIB pure_quanta
J 0
(-350 3550);
PAINT MONO (-350 3550);
DISPLAY INVISIBLE (-350 3550);
FORCEPROP 1 LAST PATH I87
J 0
(-400 3700);
DISPLAY 0.978723 (-400 3700);
PAINT WHITE (-400 3700);
DISPLAY INVISIBLE (-400 3700);
FORCEPROP 2 LAST CDS_LOCATION R1324
J 0
(-400 3750);
DISPLAY 1.021277 (-400 3750);
DISPLAY INVISIBLE (-400 3750);
FORCEPROP 2 LAST $SEC 1
J 0
(-400 3750);
DISPLAY 0.680851 (-400 3750);
PAINT MONO (-400 3750);
DISPLAY INVISIBLE (-400 3750);
FORCEPROP 2 LAST CDS_SEC 1
J 0
(-400 3750);
DISPLAY 1.021277 (-400 3750);
DISPLAY INVISIBLE (-400 3750);
FORCEADD Q_RES..1
(-350 3650);
FORCEPROP 1 LAST PART_NUMBER CS21002FB06
J 0
(-500 3575);
DISPLAY 0.638298 (-500 3575);
DISPLAY INVISIBLE (-500 3575);
FORCEPROP 1 LAST TOLERANCE 1%
J 0
(-150 3650);
DISPLAY 0.510638 (-150 3650);
FORCEPROP 1 LAST VALUE 1K
J 2
(-175 3650);
DISPLAY 0.510638 (-175 3650);
FORCEPROP 1 LAST MATERIAL CHIP
J 0
(-75 3650);
DISPLAY 0.510638 (-75 3650);
FORCEPROP 1 LAST $LOCATION R1317
J 0
(-650 3650);
DISPLAY 0.638298 (-650 3650);
FORCEPROP 1 LASTPIN (-450 3650) $PN 1
J 0
(-438 3662);
DISPLAY 0.787234 (-438 3662);
FORCEPROP 1 LASTPIN (-250 3650) $PN 2
J 0
(-288 3662);
DISPLAY 0.787234 (-288 3662);
FORCEPROP 2 LAST CDS_LIB pure_quanta
J 0
(-350 3650);
PAINT MONO (-350 3650);
DISPLAY INVISIBLE (-350 3650);
FORCEPROP 1 LAST PACK_TYPE 0402LF
J 0
(-500 3525);
DISPLAY 0.638298 (-500 3525);
DISPLAY INVISIBLE (-500 3525);
FORCEPROP 1 LAST WATTAGE 1/16W
J 2
(-125 3525);
DISPLAY 0.638298 (-125 3525);
DISPLAY INVISIBLE (-125 3525);
FORCEPROP 1 LAST PATH I88
J 0
(-400 3800);
DISPLAY 0.978723 (-400 3800);
PAINT WHITE (-400 3800);
DISPLAY INVISIBLE (-400 3800);
FORCEPROP 2 LAST CDS_LOCATION R1317
J 0
(-400 3850);
DISPLAY 1.021277 (-400 3850);
DISPLAY INVISIBLE (-400 3850);
FORCEPROP 2 LAST $SEC 1
J 0
(-400 3850);
DISPLAY 0.680851 (-400 3850);
PAINT MONO (-400 3850);
DISPLAY INVISIBLE (-400 3850);
FORCEPROP 2 LAST CDS_SEC 1
J 0
(-400 3850);
DISPLAY 1.021277 (-400 3850);
DISPLAY INVISIBLE (-400 3850);
FORCEADD Q_RES..1
(-350 3600);
FORCEPROP 1 LAST PART_NUMBER CS21002FB06
J 0
(-500 3525);
DISPLAY 0.638298 (-500 3525);
DISPLAY INVISIBLE (-500 3525);
FORCEPROP 1 LAST VALUE 1K
J 2
(-175 3600);
DISPLAY 0.510638 (-175 3600);
FORCEPROP 1 LAST TOLERANCE 1%
J 0
(-150 3600);
DISPLAY 0.510638 (-150 3600);
FORCEPROP 1 LAST MATERIAL CHIP
J 0
(-75 3600);
DISPLAY 0.510638 (-75 3600);
FORCEPROP 1 LAST $LOCATION R1320
J 0
(-650 3600);
DISPLAY 0.638298 (-650 3600);
FORCEPROP 1 LASTPIN (-450 3600) $PN 1
J 0
(-438 3612);
DISPLAY 0.787234 (-438 3612);
FORCEPROP 1 LASTPIN (-250 3600) $PN 2
J 0
(-288 3612);
DISPLAY 0.787234 (-288 3612);
FORCEPROP 2 LAST CDS_LIB pure_quanta
J 0
(-350 3600);
PAINT MONO (-350 3600);
DISPLAY INVISIBLE (-350 3600);
FORCEPROP 1 LAST WATTAGE 1/16W
J 2
(-125 3475);
DISPLAY 0.638298 (-125 3475);
DISPLAY INVISIBLE (-125 3475);
FORCEPROP 1 LAST PACK_TYPE 0402LF
J 0
(-500 3475);
DISPLAY 0.638298 (-500 3475);
DISPLAY INVISIBLE (-500 3475);
FORCEPROP 1 LAST PATH I89
J 0
(-400 3750);
DISPLAY 0.978723 (-400 3750);
PAINT WHITE (-400 3750);
DISPLAY INVISIBLE (-400 3750);
FORCEPROP 2 LAST CDS_LOCATION R1320
J 0
(-400 3800);
DISPLAY 1.021277 (-400 3800);
DISPLAY INVISIBLE (-400 3800);
FORCEPROP 2 LAST $SEC 1
J 0
(-400 3800);
DISPLAY 0.680851 (-400 3800);
PAINT MONO (-400 3800);
DISPLAY INVISIBLE (-400 3800);
FORCEPROP 2 LAST CDS_SEC 1
J 0
(-400 3800);
DISPLAY 1.021277 (-400 3800);
DISPLAY INVISIBLE (-400 3800);
FORCEADD UNIVERSAL_POWER..1
(-775 3925);
FORCEPROP 3 LASTPIN (-775 3875) SIG_NAME P1V05_PCH_AUX\g
J 0
(-765 3885);
DISPLAY 0.659574 (-765 3885);
PAINT MONO (-765 3885);
DISPLAY INVISIBLE (-765 3885);
FORCEPROP 1 LAST HDL_POWER P1V05_PCH_AUX
J 1
(-775 3975);
DISPLAY 0.702128 (-775 3975);
PAINT GREEN (-775 3975);
FORCEPROP 2 LAST CDS_LIB logical_power
J 0
(-775 3925);
PAINT MONO (-775 3925);
DISPLAY INVISIBLE (-775 3925);
FORCEPROP 1 LAST PATH I90
J 0
(-725 3950);
DISPLAY 0.872340 (-725 3950);
PAINT AQUA (-725 3950);
DISPLAY INVISIBLE (-725 3950);
FORCEADD UNIVERSAL_POWER..1
(-1200 3925);
FORCEPROP 3 LASTPIN (-1200 3875) SIG_NAME P3V3_AUX\g
J 0
(-1190 3885);
DISPLAY 0.659574 (-1190 3885);
PAINT MONO (-1190 3885);
DISPLAY INVISIBLE (-1190 3885);
FORCEPROP 1 LAST HDL_POWER P3V3_AUX
J 1
(-1200 3975);
DISPLAY 0.702128 (-1200 3975);
PAINT GREEN (-1200 3975);
FORCEPROP 2 LAST CDS_LIB logical_power
J 0
(-1200 3925);
PAINT MONO (-1200 3925);
DISPLAY INVISIBLE (-1200 3925);
FORCEPROP 1 LAST PATH I92
J 0
(-1150 3950);
DISPLAY 0.872340 (-1150 3950);
PAINT AQUA (-1150 3950);
DISPLAY INVISIBLE (-1150 3950);
FORCEADD Q_RES..1
(-350 3500);
FORCEPROP 1 LAST PART_NUMBER CS21002FB06
J 0
(-500 3425);
DISPLAY 0.638298 (-500 3425);
DISPLAY INVISIBLE (-500 3425);
FORCEPROP 1 LAST MATERIAL CHIP
J 0
(50 3500);
DISPLAY 0.638298 (50 3500);
FORCEPROP 1 LAST VALUE 1K
J 2
(-100 3500);
DISPLAY 0.638298 (-100 3500);
FORCEPROP 1 LAST TOLERANCE 1%
J 0
(-50 3500);
DISPLAY 0.638298 (-50 3500);
FORCEPROP 1 LAST $LOCATION R1325
J 0
(-650 3500);
DISPLAY 0.638298 (-650 3500);
FORCEPROP 1 LASTPIN (-450 3500) $PN 1
J 0
(-438 3512);
DISPLAY 0.787234 (-438 3512);
FORCEPROP 1 LASTPIN (-250 3500) $PN 2
J 0
(-288 3512);
DISPLAY 0.787234 (-288 3512);
FORCEPROP 2 LAST CDS_LIB pure_quanta
J 0
(-350 3500);
PAINT MONO (-350 3500);
DISPLAY INVISIBLE (-350 3500);
FORCEPROP 1 LAST PACK_TYPE 0402LF
J 0
(-500 3375);
DISPLAY 0.638298 (-500 3375);
DISPLAY INVISIBLE (-500 3375);
FORCEPROP 1 LAST WATTAGE 1/16W
J 2
(-125 3375);
DISPLAY 0.638298 (-125 3375);
DISPLAY INVISIBLE (-125 3375);
FORCEPROP 1 LAST PATH I93
J 0
(-400 3650);
DISPLAY 0.978723 (-400 3650);
PAINT WHITE (-400 3650);
DISPLAY INVISIBLE (-400 3650);
FORCEPROP 2 LAST CDS_LOCATION R1325
J 0
(-400 3700);
DISPLAY 1.021277 (-400 3700);
DISPLAY INVISIBLE (-400 3700);
FORCEPROP 2 LAST $SEC 1
J 0
(-400 3700);
DISPLAY 0.680851 (-400 3700);
PAINT MONO (-400 3700);
DISPLAY INVISIBLE (-400 3700);
FORCEPROP 2 LAST CDS_SEC 1
J 0
(-400 3700);
DISPLAY 1.021277 (-400 3700);
DISPLAY INVISIBLE (-400 3700);
FORCEADD UNIVERSAL_GND..1
(-775 3225);
FORCEPROP 3 LASTPIN (-775 3275) SIG_NAME GND\g
J 0
(-765 3285);
DISPLAY 0.659574 (-765 3285);
PAINT MONO (-765 3285);
DISPLAY INVISIBLE (-765 3285);
FORCEPROP 2 LAST CDS_LIB logical_power
J 0
(-775 3225);
PAINT MONO (-775 3225);
DISPLAY INVISIBLE (-775 3225);
FORCEPROP 1 LAST HDL_POWER GND
J 1
(-750 3150);
DISPLAY 0.872340 (-750 3150);
PAINT GREEN (-750 3150);
DISPLAY INVISIBLE (-750 3150);
FORCEPROP 1 LAST PATH I98
J 0
(-700 3225);
DISPLAY 0.872340 (-700 3225);
PAINT AQUA (-700 3225);
DISPLAY INVISIBLE (-700 3225);
FORCEPROP 2 LAST ROOM IO_SLOT
J 1
(-1000 3300);
DISPLAY 0.744681 (-1000 3300);
DISPLAY INVISIBLE (-1000 3300);
FORCEADD UNIVERSAL_POWER..1
(3575 4275);
FORCEPROP 3 LASTPIN (3575 4225) SIG_NAME P3V3_AUX\g
J 0
(3585 4235);
DISPLAY 0.659574 (3585 4235);
PAINT MONO (3585 4235);
DISPLAY INVISIBLE (3585 4235);
FORCEPROP 1 LAST HDL_POWER P3V3_AUX
J 1
(3575 4325);
DISPLAY 0.872340 (3575 4325);
PAINT GREEN (3575 4325);
FORCEPROP 2 LAST CDS_LIB logical_power
J 0
(3575 4275);
PAINT MONO (3575 4275);
DISPLAY INVISIBLE (3575 4275);
FORCEPROP 1 LAST PATH I99
J 0
(3625 4300);
DISPLAY 0.872340 (3625 4300);
PAINT AQUA (3625 4300);
DISPLAY INVISIBLE (3625 4300);
FORCEADD QUANTA_TITLE_BLOCK_C..1
(5250 -1650);
FORCEPROP 0 LAST CDS_CON_LAST_MODIFIED Fri Aug 25 14:03:16 2023
J 0
(3365 -1635);
PAINT MONO (3365 -1635);
DISPLAY INVISIBLE (3365 -1635);
FORCEPROP 2 LAST CUSTOM_TXT_CDS <XR_PAGE_TITLE>
J 0
(-2640 3600);
DISPLAY 0.638298 (-2640 3600);
PAINT PINK (-2640 3600);
DISPLAY INVISIBLE (-2640 3600);
FORCEPROP 2 LAST CUSTOM_TXT_CDS CR-166 : @ES_MB_LIB.ES_MB(SCH_1):PAGE166
J 0
(-2640 3600);
DISPLAY 0.638298 (-2640 3600);
PAINT PINK (-2640 3600);
DISPLAY INVISIBLE (-2640 3600);
FORCEPROP 2 LAST CUSTOM_TXT_CDS <CON_PAGE_NUM> OF <CON_TOTAL_PAGES>
J 0
(4775 -1650);
DISPLAY 0.978723 (4775 -1650);
FORCEPROP 2 LAST CUSTOM_TXT_CDS <Q_REV>
J 0
(5066 -1547);
DISPLAY 1.212766 (5066 -1547);
FORCEPROP 2 LAST CUSTOM_TXT_CDS <Q_PROJ>
J 0
(2950 -1525);
DISPLAY 1.212766 (2950 -1525);
FORCEPROP 2 LAST CUSTOM_TXT_CDS <CON_LAST_MODIFIED>
J 0
(3365 -1635);
DISPLAY 0.978723 (3365 -1635);
FORCEPROP 2 LAST CUSTOM_TXT_CDS <Q_NUMBER>
J 0
(3847 -1547);
DISPLAY 1.212766 (3847 -1547);
FORCEPROP 1 LAST CUSTOM_TXT_CDS <NAME_2>
J 0
(2075 -1600);
FORCEPROP 1 LAST CUSTOM_TXT_CDS <NAME_1>
J 0
(2075 -1475);
FORCEPROP 1 LAST Q_TITLE PCH SIDEBAND: HW STRAPS (4/4)
J 0
(-4091 -1624);
DISPLAY 1.957447 (-4091 -1624);
PAINT GREEN (-4091 -1624);
FORCEPROP 1 LAST Q_DEPT 
J 1
(1487 -1601);
DISPLAY 1.957447 (1487 -1601);
PAINT GREEN (1487 -1601);
FORCEPROP 2 LAST CDS_XR_PAGE_TITLE CR-201 : @S9S_MB_2U_LIB.S9S_MB_2U(SCH_1):PAGE201
J 0
(-2640 3600);
DISPLAY 0.638298 (-2640 3600);
PAINT PINK (-2640 3600);
DISPLAY INVISIBLE (-2640 3600);
FORCEPROP 1 LAST COMMENT_BODY TRUE
J 0
(5262 -1663);
DISPLAY 0.978723 (5262 -1663);
PAINT GREEN (5262 -1663);
DISPLAY INVISIBLE (5262 -1663);
FORCEPROP 2 LAST CDS_LIB pure_quanta
J 0
(5250 -1650);
PAINT MONO (5250 -1650);
DISPLAY INVISIBLE (5250 -1650);
FORCEPROP 1 LAST CDS_LMAN_SYM_OUTLINE -9475,6775,100,-125
J 0
(5250 -1650);
DISPLAY 0.468085 (5250 -1650);
PAINT GREEN (5250 -1650);
DISPLAY INVISIBLE (5250 -1650);
FORCEPROP 2 LAST PAGE_BORDER TRUE
J 0
(-2640 3600);
DISPLAY 0.638298 (-2640 3600);
PAINT PINK (-2640 3600);
DISPLAY INVISIBLE (-2640 3600);
FORCEADD DESIGN_NOTE..1
(-3600 1050);
FORCEPROP 0 LAST S1 SW2 BIT1: FLASH SECURITY OVERRIDE STRAP
J 0
(-3800 900);
DISPLAY 1.021277 (-3800 900);
PAINT WHITE (-3800 900);
FORCEPROP 2 LAST CDS_LIB logical_power
J 0
(-3600 1050);
PAINT MONO (-3600 1050);
DISPLAY INVISIBLE (-3600 1050);
FORCEPROP 1 LAST COMMENT_BODY TRUE
J 0
(-3575 1150);
DISPLAY 0.978723 (-3575 1150);
DISPLAY INVISIBLE (-3575 1150);
FORCEADD DESIGN_NOTE..1
(-3600 1975);
FORCEPROP 0 LAST S1 SW1 BIT4: BIOS IMAGE SWAP
J 0
(-3800 1825);
DISPLAY 1.021277 (-3800 1825);
PAINT WHITE (-3800 1825);
FORCEPROP 2 LAST CDS_LIB logical_power
J 0
(-3600 1975);
PAINT MONO (-3600 1975);
DISPLAY INVISIBLE (-3600 1975);
FORCEPROP 1 LAST COMMENT_BODY TRUE
J 0
(-3575 2075);
DISPLAY 0.978723 (-3575 2075);
DISPLAY INVISIBLE (-3575 2075);
FORCEADD DESIGN_NOTE..1
(-3600 -725);
FORCEPROP 0 LAST S1 SW2 BIT4: PASSWORD CLEAR
J 0
(-3800 -875);
DISPLAY 1.021277 (-3800 -875);
PAINT WHITE (-3800 -875);
FORCEPROP 2 LAST CDS_LIB logical_power
J 0
(-3600 -725);
PAINT MONO (-3600 -725);
DISPLAY INVISIBLE (-3600 -725);
FORCEPROP 1 LAST COMMENT_BODY TRUE
J 0
(-3575 -625);
DISPLAY 0.978723 (-3575 -625);
DISPLAY INVISIBLE (-3575 -625);
FORCEADD DESIGN_NOTE..1
(-3600 -125);
FORCEPROP 0 LAST S1 SW2 BIT3: ME FW UPDATE
J 0
(-3800 -275);
DISPLAY 1.021277 (-3800 -275);
PAINT WHITE (-3800 -275);
FORCEPROP 2 LAST CDS_LIB logical_power
J 0
(-3600 -125);
PAINT MONO (-3600 -125);
DISPLAY INVISIBLE (-3600 -125);
FORCEPROP 1 LAST COMMENT_BODY TRUE
J 0
(-3575 -25);
DISPLAY 0.978723 (-3575 -25);
DISPLAY INVISIBLE (-3575 -25);
FORCEADD DESIGN_NOTE..1
(-3600 3175);
FORCEPROP 0 LAST S1 SW1 BIT2: BIOS RCVR
J 0
(-3800 3025);
DISPLAY 1.021277 (-3800 3025);
PAINT WHITE (-3800 3025);
FORCEPROP 2 LAST CDS_LIB logical_power
J 0
(-3600 3175);
PAINT MONO (-3600 3175);
DISPLAY INVISIBLE (-3600 3175);
FORCEPROP 1 LAST COMMENT_BODY TRUE
J 0
(-3575 3275);
DISPLAY 0.978723 (-3575 3275);
DISPLAY INVISIBLE (-3575 3275);
FORCEADD DESIGN_NOTE..1
(-3600 2575);
FORCEPROP 0 LAST S1 SW1 BIT3: BIOS SWAP OVERRIDE
J 0
(-3800 2425);
DISPLAY 1.021277 (-3800 2425);
PAINT WHITE (-3800 2425);
FORCEPROP 2 LAST CDS_LIB logical_power
J 0
(-3600 2575);
PAINT MONO (-3600 2575);
DISPLAY INVISIBLE (-3600 2575);
FORCEPROP 1 LAST COMMENT_BODY TRUE
J 0
(-3575 2675);
DISPLAY 0.978723 (-3575 2675);
DISPLAY INVISIBLE (-3575 2675);
FORCEADD DESIGN_NOTE..1
(-3600 450);
FORCEPROP 0 LAST S1 SW2 BIT2: CMOS CLEAR
J 0
(-3800 300);
DISPLAY 1.021277 (-3800 300);
PAINT WHITE (-3800 300);
FORCEPROP 2 LAST CDS_LIB logical_power
J 0
(-3600 450);
PAINT MONO (-3600 450);
DISPLAY INVISIBLE (-3600 450);
FORCEPROP 1 LAST COMMENT_BODY TRUE
J 0
(-3575 550);
DISPLAY 0.978723 (-3575 550);
DISPLAY INVISIBLE (-3575 550);
FORCEADD DESIGN_NOTE..1
(-3575 3800);
FORCEPROP 0 LAST S1 SW1 BIT1: ESPI ENABLE
J 0
(-3775 3650);
DISPLAY 1.021277 (-3775 3650);
PAINT WHITE (-3775 3650);
FORCEPROP 2 LAST CDS_LIB logical_power
J 0
(-3575 3800);
PAINT MONO (-3575 3800);
DISPLAY INVISIBLE (-3575 3800);
FORCEPROP 1 LAST COMMENT_BODY TRUE
J 0
(-3550 3900);
DISPLAY 0.978723 (-3550 3900);
DISPLAY INVISIBLE (-3550 3900);
WIRE 16 -1 (-775 3875)(-775 3650);
WIRE 16 -1 (-1200 3875)(-1200 3700);
WIRE 16 -1 (3575 4050)(3575 4225);
WIRE 16 -1 (4000 4150)(4000 4225);
WIRE 16 -1 (4250 4150)(4000 4150);
WIRE 16 -1 (4000 4050)(4000 4150);
WIRE 16 -1 (2900 2325)(2900 2150);
WIRE 16 -1 (-775 3400)(-775 3275);
WIRE 16 -1 (-775 3450)(-775 3400);
WIRE 16 -1 (-775 3400)(-450 3400);
WIRE 16 -1 (3025 2850)(3025 2925);
WIRE 16 -1 (2800 2850)(2800 2925);
WIRE 16 -1 (2575 2850)(2575 2925);
WIRE 16 -1 (-975 1500)(-975 1550);
WIRE 16 -1 (3000 1025)(3000 950);
WIRE 16 3135 (-3825 725)(-3825 600);
WIRE 16 3135 (-3825 600)(-3325 600);
WIRE 16 3135 (-3325 600)(-1975 600);
WIRE 16 3135 (-3825 850)(-3825 725);
WIRE 16 3135 (-3825 725)(-1975 725);
WIRE 16 3135 (-1975 600)(-1975 725);
WIRE 16 3135 (-1975 725)(-1975 850);
WIRE 16 3135 (-3825 850)(-3325 850);
WIRE 16 3135 (-3325 850)(-3325 600);
WIRE 16 3135 (-3325 850)(-1975 850);
WIRE 16 3135 (-3325 250)(-3325 0);
WIRE 16 3135 (-3825 250)(-3325 250);
WIRE 16 3135 (-3825 0)(-3325 0);
WIRE 16 3135 (-3325 250)(-1975 250);
WIRE 16 3135 (-3325 0)(-1975 0);
WIRE 16 3135 (-1975 0)(-1975 125);
WIRE 16 3135 (-1975 125)(-1975 250);
WIRE 16 3135 (-3825 125)(-3825 0);
WIRE 16 3135 (-3825 250)(-3825 125);
WIRE 16 3135 (-3825 125)(-1975 125);
WIRE 16 3135 (-3300 3600)(-3300 3350);
WIRE 16 3135 (-3800 3350)(-3300 3350);
WIRE 16 3135 (-3800 3600)(-3300 3600);
WIRE 16 3135 (-3300 3350)(-1950 3350);
WIRE 16 3135 (-3300 3600)(-1950 3600);
WIRE 16 3135 (-1950 3475)(-1950 3600);
WIRE 16 3135 (-1950 3350)(-1950 3475);
WIRE 16 3135 (-3800 3600)(-3800 3475);
WIRE 16 3135 (-3800 3475)(-3800 3350);
WIRE 16 3135 (-3800 3475)(-1950 3475);
WIRE 16 3135 (-3825 2850)(-3825 2725);
WIRE 16 3135 (-3825 2725)(-3325 2725);
WIRE 16 3135 (-3325 2725)(-1975 2725);
WIRE 16 3135 (-3825 2975)(-3825 2850);
WIRE 16 3135 (-3825 2850)(-1975 2850);
WIRE 16 3135 (-1975 2725)(-1975 2850);
WIRE 16 3135 (-1975 2850)(-1975 2975);
WIRE 16 3135 (-3825 2975)(-3325 2975);
WIRE 16 3135 (-3325 2975)(-3325 2725);
WIRE 16 3135 (-3325 2975)(-1975 2975);
WIRE 16 -1 (-775 3550)(-450 3550);
WIRE 16 -1 (-775 3550)(-775 3450);
WIRE 16 -1 (-775 3450)(-450 3450);
WIRE 16 -1 (1125 3600)(-250 3600);
FORCEPROP 0 LAST CDS_PHYS_NET_NAME PU_SWAP_OVERRIDE_N
J 0
(388 3641);
PAINT MONO (388 3641);
DISPLAY INVISIBLE (388 3641);
FORCEPROP 2 LAST SIG_NAME PU_SWAP_OVERRIDE_N
J 0
(315 3610);
DISPLAY 0.680851 (315 3610);
PAINT WHITE (315 3610);
WIRE 16 -1 (1125 3450)(-250 3450);
FORCEPROP 0 LAST CDS_PHYS_NET_NAME PD_ME_RCVR_N
J 0
(438 3491);
PAINT MONO (438 3491);
DISPLAY INVISIBLE (438 3491);
FORCEPROP 2 LAST SIG_NAME PD_ME_RCVR_N
J 0
(313 3459);
DISPLAY 0.680851 (313 3459);
PAINT WHITE (313 3459);
WIRE 16 -1 (1125 3400)(-250 3400);
FORCEPROP 0 LAST CDS_PHYS_NET_NAME PD_PASSWORD_CLEAR
J 0
(388 3441);
PAINT MONO (388 3441);
DISPLAY INVISIBLE (388 3441);
FORCEPROP 2 LAST SIG_NAME PD_PASSWORD_CLEAR
J 0
(313 3409);
DISPLAY 0.680851 (313 3409);
PAINT WHITE (313 3409);
WIRE 16 3135 (-3325 2375)(-3325 2125);
WIRE 16 3135 (-3825 2125)(-3325 2125);
WIRE 16 3135 (-3825 2375)(-3325 2375);
WIRE 16 3135 (-3325 2125)(-1975 2125);
WIRE 16 3135 (-3325 2375)(-1975 2375);
WIRE 16 3135 (-1975 2250)(-1975 2375);
WIRE 16 3135 (-1975 2125)(-1975 2250);
WIRE 16 3135 (-3825 2375)(-3825 2250);
WIRE 16 3135 (-3825 2250)(-3825 2125);
WIRE 16 3135 (-3825 2250)(-1975 2250);
WIRE 16 3135 (-1975 1525)(-1975 1650);
WIRE 16 3135 (-3825 1650)(-3825 1525);
WIRE 16 3135 (-3825 1650)(-1975 1650);
WIRE 16 3135 (-1975 1650)(-1975 1775);
WIRE 16 3135 (-3825 1525)(-3325 1525);
WIRE 16 3135 (-3325 1525)(-1975 1525);
WIRE 16 3135 (-3325 1775)(-3325 1525);
WIRE 16 3135 (-3325 1775)(-1975 1775);
WIRE 16 3135 (-3825 1775)(-3825 1650);
WIRE 16 3135 (-3825 1775)(-3325 1775);
WIRE 16 3135 (-3325 -325)(-3325 -575);
WIRE 16 3135 (-3825 -575)(-3325 -575);
WIRE 16 3135 (-3825 -325)(-3325 -325);
WIRE 16 3135 (-3325 -325)(-1975 -325);
WIRE 16 3135 (-3325 -575)(-1975 -575);
WIRE 16 3135 (-1975 -575)(-1975 -450);
WIRE 16 3135 (-1975 -450)(-1975 -325);
WIRE 16 3135 (-3825 -325)(-3825 -450);
WIRE 16 3135 (-3825 -450)(-3825 -575);
WIRE 16 3135 (-3825 -450)(-1975 -450);
WIRE 16 -1 (1125 3500)(-250 3500);
FORCEPROP 0 LAST CDS_PHYS_NET_NAME RST_RTCRST_N
J 0
(438 3541);
PAINT MONO (438 3541);
DISPLAY INVISIBLE (438 3541);
FORCEPROP 2 LAST SIG_NAME PU_FLASH_SECURITY_STRAP
J 0
(313 3509);
DISPLAY 0.680851 (313 3509);
PAINT WHITE (313 3509);
WIRE 16 -1 (1125 3550)(-250 3550);
FORCEPROP 0 LAST CDS_PHYS_NET_NAME PD_BIOS_IMAGE_SWAP_N
J 0
(438 3591);
PAINT MONO (438 3591);
DISPLAY INVISIBLE (438 3591);
FORCEPROP 2 LAST SIG_NAME PD_BIOS_IMAGE_SWAP_N
J 0
(315 3560);
DISPLAY 0.680851 (315 3560);
PAINT WHITE (315 3560);
WIRE 16 -1 (1125 3650)(-250 3650);
FORCEPROP 0 LAST CDS_PHYS_NET_NAME PU_BIOS_RCVR_BOOT
J 0
(438 3691);
PAINT MONO (438 3691);
DISPLAY INVISIBLE (438 3691);
FORCEPROP 2 LAST SIG_NAME PU_BIOS_RCVR_BOOT
J 0
(315 3660);
DISPLAY 0.680851 (315 3660);
PAINT WHITE (315 3660);
WIRE 16 -1 (1125 3700)(-250 3700);
FORCEPROP 0 LAST CDS_PHYS_NET_NAME PU_ESPI_ENABLE_STRAP
J 0
(188 3741);
PAINT MONO (188 3741);
DISPLAY INVISIBLE (188 3741);
FORCEPROP 2 LAST SIG_NAME PU_ESPI_ENABLE_STRAP
J 0
(315 3710);
DISPLAY 0.680851 (315 3710);
PAINT WHITE (315 3710);
WIRE 16 -1 (-1200 3500)(-450 3500);
WIRE 16 -1 (-1200 3500)(-1200 3600);
WIRE 16 -1 (-450 3600)(-1200 3600);
WIRE 16 -1 (-1200 3700)(-1200 3600);
WIRE 16 -1 (-450 3700)(-1200 3700);
WIRE 16 -1 (1625 3400)(4000 3400);
FORCEPROP 0 LAST CDS_PHYS_NET_NAME FM_PASSWORD_CLEAR_N
J 0
(1688 3441);
PAINT MONO (1688 3441);
DISPLAY INVISIBLE (1688 3441);
FORCEPROP 2 LAST SIG_NAME FM_PASSWORD_CLEAR_N
J 0
(1763 3409);
DISPLAY 0.680851 (1763 3409);
PAINT WHITE (1763 3409);
WIRE 16 -1 (4450 3400)(4000 3400);
WIRE 16 -1 (4000 3850)(4000 3400);
WIRE 16 -1 (1625 3450)(4250 3450);
FORCEPROP 0 LAST CDS_PHYS_NET_NAME FM_ME_RCVR_N
J 0
(1688 3491);
PAINT MONO (1688 3491);
DISPLAY INVISIBLE (1688 3491);
FORCEPROP 2 LAST SIG_NAME FM_ME_RCVR_N
J 0
(1763 3459);
DISPLAY 0.680851 (1763 3459);
PAINT WHITE (1763 3459);
WIRE 16 -1 (4250 3850)(4250 3450);
WIRE 16 -1 (4450 3450)(4250 3450);
WIRE 16 -1 (-775 3650)(-450 3650);
WIRE 16 -1 (2575 3700)(1625 3700);
FORCEPROP 0 LAST CDS_PHYS_NET_NAME JTAG_TRC_PCH_PTI<6>
J 0
(1688 3741);
PAINT MONO (1688 3741);
DISPLAY INVISIBLE (1688 3741);
FORCEPROP 2 LAST SIG_NAME JTAG_TRC_PCH_PTI<6>
J 0
(1763 3709);
DISPLAY 0.680851 (1763 3709);
PAINT WHITE (1763 3709);
WIRE 16 -1 (2575 3125)(2575 3700);
WIRE 16 -1 (4450 3700)(2575 3700);
WIRE 16 -1 (1625 3650)(2800 3650);
FORCEPROP 0 LAST CDS_PHYS_NET_NAME FM_PCH_BIOS_RCVR_MODE
J 0
(1688 3691);
PAINT MONO (1688 3691);
DISPLAY INVISIBLE (1688 3691);
FORCEPROP 2 LAST SIG_NAME FM_PCH_BIOS_RCVR_MODE
J 0
(1763 3659);
DISPLAY 0.680851 (1763 3659);
PAINT WHITE (1763 3659);
WIRE 16 -1 (4450 3650)(2800 3650);
WIRE 16 -1 (2800 3125)(2800 3650);
WIRE 16 -1 (1625 3600)(3025 3600);
FORCEPROP 0 LAST CDS_PHYS_NET_NAME FM_ADR_COMPLETE
J 0
(1688 3641);
PAINT MONO (1688 3641);
DISPLAY INVISIBLE (1688 3641);
FORCEPROP 2 LAST SIG_NAME FM_ADR_COMPLETE
J 0
(1763 3609);
DISPLAY 0.680851 (1763 3609);
PAINT WHITE (1763 3609);
WIRE 16 -1 (4450 3600)(3025 3600);
WIRE 16 -1 (3025 3125)(3025 3600);
WIRE 16 -1 (3575 3550)(1625 3550);
FORCEPROP 0 LAST CDS_PHYS_NET_NAME FM_BIOS_IMAGE_SWAP_N
J 0
(1688 3591);
PAINT MONO (1688 3591);
DISPLAY INVISIBLE (1688 3591);
FORCEPROP 2 LAST SIG_NAME FM_BIOS_IMAGE_SWAP_N
J 0
(1763 3559);
DISPLAY 0.680851 (1763 3559);
PAINT WHITE (1763 3559);
WIRE 16 -1 (3575 3850)(3575 3550);
WIRE 16 -1 (4450 3550)(3575 3550);
WIRE 16 -1 (4450 3500)(1625 3500);
FORCEPROP 0 LAST CDS_PHYS_NET_NAME FM_FLASH_SECURITY_STRAP
J 0
(1688 3541);
PAINT MONO (1688 3541);
DISPLAY INVISIBLE (1688 3541);
FORCEPROP 2 LAST SIG_NAME FM_FLASH_SECURITY_STRAP
J 0
(1763 3509);
DISPLAY 0.680851 (1763 3509);
PAINT WHITE (1763 3509);
WIRE 16 -1 (-975 1550)(-650 1550);
WIRE 16 -1 (4250 4050)(4250 4150);
WIRE 16 -1 (3000 1225)(3000 1550);
WIRE 16 -1 (4200 1550)(3000 1550);
WIRE 16 -1 (2900 1550)(3000 1550);
WIRE 16 -1 (2900 1950)(2900 1550);
WIRE 16 -1 (1375 1550)(1450 1550);
FORCEPROP 0 LAST CDS_PHYS_NET_NAME RST_RTCRST_N
J 0
(1438 1591);
PAINT MONO (1438 1591);
DISPLAY INVISIBLE (1438 1591);
WIRE 16 -1 (1450 1550)(2900 1550);
FORCEPROP 2 LAST SIG_NAME RST_RTCRST_N
J 0
(1513 1559);
DISPLAY 0.680851 (1513 1559);
PAINT WHITE (1513 1559);
WIRE 16 -1 (1450 1500)(1450 1550);
WIRE 16 -1 (1375 1500)(1450 1500);
WIRE 16 -1 (825 1550)(-450 1550);
FORCEPROP 0 LAST CDS_PHYS_NET_NAME RST_RTCRST_N
J 0
(-12 1591);
PAINT MONO (-12 1591);
DISPLAY INVISIBLE (-12 1591);
FORCEPROP 2 LAST SIG_NAME PD_RST_RTCRST_N
J 0
(113 1559);
DISPLAY 0.680851 (113 1559);
PAINT WHITE (113 1559);
WIRE 16 -1 (925 1550)(825 1550);
WIRE 16 -1 (825 1500)(825 1550);
WIRE 16 -1 (925 1500)(825 1500);
WIRE 16 3135 (-1975 -1175)(-1975 -1050);
WIRE 16 3135 (-3825 -1050)(-3825 -1175);
WIRE 16 3135 (-3825 -1050)(-1975 -1050);
WIRE 16 3135 (-1975 -1050)(-1975 -925);
WIRE 16 3135 (-3825 -1175)(-3325 -1175);
WIRE 16 3135 (-3325 -1175)(-1975 -1175);
WIRE 16 3135 (-3325 -925)(-3325 -1175);
WIRE 16 3135 (-3325 -925)(-1975 -925);
WIRE 16 3135 (-3825 -925)(-3825 -1050);
WIRE 16 3135 (-3825 -925)(-3325 -925);
DOT 1 (-3300 3600);
DOT 1 (-775 3450);
DOT 1 (2575 3700);
DOT 1 (-3325 0);
DOT 1 (-3325 600);
DOT 1 (-3825 725);
DOT 1 (-1975 125);
DOT 1 (-3325 850);
DOT 1 (-3325 250);
DOT 1 (-3825 125);
DOT 1 (-1975 -450);
DOT 1 (-1975 -1050);
DOT 1 (-3325 -325);
DOT 1 (-3325 -925);
DOT 1 (-3325 -575);
DOT 1 (-3825 -450);
DOT 1 (-3325 -1175);
DOT 1 (-3825 -1050);
DOT 1 (-1975 1650);
DOT 1 (-3325 2125);
DOT 1 (-3325 2375);
DOT 1 (-3825 2250);
DOT 1 (-3325 1775);
DOT 1 (-3325 1525);
DOT 1 (-3825 1650);
DOT 1 (-1975 725);
DOT 1 (-1950 3475);
DOT 1 (-3300 3350);
DOT 1 (-3800 3475);
DOT 1 (-3825 2850);
DOT 1 (-3325 2975);
DOT 1 (-3325 2725);
DOT 1 (-1975 2850);
DOT 1 (-1975 2250);
DOT 1 (3575 3550);
DOT 1 (3025 3600);
DOT 1 (2800 3650);
DOT 1 (3000 1550);
DOT 1 (2900 1550);
DOT 1 (4000 3400);
DOT 1 (4250 3450);
DOT 1 (4000 4150);
DOT 1 (825 1550);
DOT 1 (1450 1550);
DOT 1 (-1200 3600);
DOT 1 (-1200 3700);
DOT 1 (-775 3400);
FORCENOTE
OPEN(SHORT)  SECURITY ENABLE
(-3775 650) 0;
DISPLAY LEFT (-3775 650);
DISPLAY 0.808511 (-3775 650);
PAINT YELLOW (-3775 650);
FORCENOTE
OPEN(SHORT)  PASSWORD CLEAR
(-3775 -1125) 0;
DISPLAY LEFT (-3775 -1125);
DISPLAY 0.808511 (-3775 -1125);
PAINT YELLOW (-3775 -1125);
FORCENOTE
OFF(OPEN)    NORMAL (DEFAULT)
(-3775 -1000) 0;
DISPLAY LEFT (-3775 -1000);
DISPLAY 0.808511 (-3775 -1000);
PAINT YELLOW (-3775 -1000);
FORCENOTE
OPEN(SHORT)  ME FORCE UPDATE
(-3775 -525) 0;
DISPLAY LEFT (-3775 -525);
DISPLAY 0.808511 (-3775 -525);
PAINT YELLOW (-3775 -525);
FORCENOTE
OFF(OPEN)    NORMAL RTC RESET (DEFAULT)
(-3775 -400) 0;
DISPLAY LEFT (-3775 -400);
DISPLAY 0.808511 (-3775 -400);
PAINT YELLOW (-3775 -400);
FORCENOTE
OFF(OPEN)    SECURITY DISABLE (DEFAULT)
(-3775 775) 0;
DISPLAY LEFT (-3775 775);
DISPLAY 0.808511 (-3775 775);
PAINT YELLOW (-3775 775);
FORCENOTE
OFF(OPEN)    NORMAL RTC RESET (DEFAULT)
(-3775 175) 0;
DISPLAY LEFT (-3775 175);
DISPLAY 0.808511 (-3775 175);
PAINT YELLOW (-3775 175);
FORCENOTE
OPEN(SHORT)  CLEAR RTC REGISTERS
(-3775 50) 0;
DISPLAY LEFT (-3775 50);
DISPLAY 0.808511 (-3775 50);
PAINT YELLOW (-3775 50);
FORCENOTE
GPP_L_4
(-3200 -150) 0;
DISPLAY LEFT (-3200 -150);
DISPLAY 1.595745 (-3200 -150);
PAINT SKYBLUE (-3200 -150);
FORCENOTE
OPEN(SHORT)  BIOS IMAGE SWAP
(-3775 1575) 0;
DISPLAY LEFT (-3775 1575);
DISPLAY 0.808511 (-3775 1575);
PAINT YELLOW (-3775 1575);
FORCENOTE
OFF(OPEN)    NORMAL (DEFAULT)
(-3775 1700) 0;
DISPLAY LEFT (-3775 1700);
DISPLAY 0.808511 (-3775 1700);
PAINT YELLOW (-3775 1700);
FORCENOTE
OPEN(SHORT)  ENABLE OVERRIDE
(-3775 2175) 0;
DISPLAY LEFT (-3775 2175);
DISPLAY 0.808511 (-3775 2175);
PAINT YELLOW (-3775 2175);
FORCENOTE
OFF(OPEN)    DISABLE OVERRIDE (DEFAULT)
(-3775 2300) 0;
DISPLAY LEFT (-3775 2300);
DISPLAY 0.808511 (-3775 2300);
PAINT YELLOW (-3775 2300);
FORCENOTE
OPEN(SHORT)  RECOVER BIOS
(-3775 2775) 0;
DISPLAY LEFT (-3775 2775);
DISPLAY 0.808511 (-3775 2775);
PAINT YELLOW (-3775 2775);
FORCENOTE
OFF(OPEN)    NORMAL (DEFAULT)
(-3775 2900) 0;
DISPLAY LEFT (-3775 2900);
DISPLAY 0.808511 (-3775 2900);
PAINT YELLOW (-3775 2900);
FORCENOTE
OPEN(SHORT)  DISABLE ESPI
(-3750 3400) 0;
DISPLAY LEFT (-3750 3400);
DISPLAY 0.808511 (-3750 3400);
PAINT YELLOW (-3750 3400);
FORCENOTE
OFF(OPEN)    NORMAL (DEFAULT)
(-3750 3525) 0;
DISPLAY LEFT (-3750 3525);
DISPLAY 0.808511 (-3750 3525);
PAINT YELLOW (-3750 3525);
FORCENOTE
GPP_M_11
(-3200 3150) 0;
DISPLAY LEFT (-3200 3150);
DISPLAY 1.595745 (-3200 3150);
PAINT SKYBLUE (-3200 3150);
FORCENOTE
GPP_D_6
(-3200 1025) 0;
DISPLAY LEFT (-3200 1025);
DISPLAY 1.595745 (-3200 1025);
PAINT SKYBLUE (-3200 1025);
FORCENOTE
GPP_D_19
(-3200 1950) 0;
DISPLAY LEFT (-3200 1950);
DISPLAY 1.595745 (-3200 1950);
PAINT SKYBLUE (-3200 1950);
FORCENOTE
20210922 MODIFY FOR GT
(-150 4650) 0;
DISPLAY LEFT (-150 4650);
DISPLAY 2.510638 (-150 4650);
PAINT PINK (-150 4650);
FORCENOTE
GPP_D_13
(-3200 2550) 0;
DISPLAY LEFT (-3200 2550);
DISPLAY 1.595745 (-3200 2550);
PAINT SKYBLUE (-3200 2550);
FORCENOTE
GPP_L_5
(-3200 -750) 0;
DISPLAY LEFT (-3200 -750);
DISPLAY 1.595745 (-3200 -750);
PAINT SKYBLUE (-3200 -750);
FORCENOTE
GPPC_B_13
(-3175 3775) 0;
DISPLAY LEFT (-3175 3775);
DISPLAY 1.595745 (-3175 3775);
PAINT SKYBLUE (-3175 3775);
QUIT
